FILE_TYPE=LIBRARY_PARTS;
primitive 'TPS71715DCKR';
  pin
    'GND':
      PIN_NUMBER='(2)';
      PINUSE='POWER';
      NO_LOAD_CHECK='Both';
      NO_IO_CHECK='Both';
      NO_ASSERT_CHECK='TRUE';
      NO_DIR_CHECK='TRUE';
      ALLOW_CONNECT='TRUE';
    'EN':
      PIN_NUMBER='(3)';
      INPUT_LOAD='(-0.01,0.01)';
    'IN':
      PIN_NUMBER='(1)';
      INPUT_LOAD='(-0.01,0.01)';
    'NR||FB':
      PIN_NUMBER='(4)';
      OUTPUT_LOAD='(1.0,-1.0)';
    'OUT':
      PIN_NUMBER='(5)';
      OUTPUT_LOAD='(1.0,-1.0)';
  end_pin;
  body
    PART_NAME='TPS71715DCKR';
    BODY_NAME='TPS71715DCKR';
    PHYS_DES_PREFIX='U';
    CLASS='IC';
  end_body;
end_primitive;

END.
